(kicad_pcb
	(version 20260206)
	(generator "pcbnew")
	(generator_version "10.0")
	(general
		(thickness 1.6)
		(legacy_teardrops no)
	)
	(paper "A4")
	(title_block
		(title "04192023_DAF0TMB3IC0_F0TG_MB_C_brd_V02_OCP.brd")
		(comment 1 "Grand Teton / footprints 6843-6849 of 8354")
	)
	(layers
		(0 "F.Cu" signal "TOP")
		(4 "In1.Cu" signal "GND")
		(6 "In2.Cu" signal "IN1")
		(8 "In3.Cu" signal "GND1")
		(10 "In4.Cu" signal "IN2")
		(12 "In5.Cu" signal "GND2")
		(14 "In6.Cu" signal "IN3")
		(16 "In7.Cu" signal "GND3")
		(18 "In8.Cu" signal "VCC")
		(20 "In9.Cu" signal "VCC1")
		(22 "In10.Cu" signal "GND4")
		(24 "In11.Cu" signal "IN4")
		(26 "In12.Cu" signal "GND5")
		(28 "In13.Cu" signal "IN5")
		(30 "In14.Cu" signal "GND6")
		(32 "In15.Cu" signal "IN6")
		(34 "In16.Cu" signal "GND7")
		(2 "B.Cu" signal "BOTTOM")
		(9 "F.Adhes" user "F.Adhesive")
		(11 "B.Adhes" user "B.Adhesive")
		(13 "F.Paste" user "Package Geometry/Pastemask Top")
		(15 "B.Paste" user "Package Geometry/Pastemask Bottom")
		(5 "F.SilkS" user "Ref Des/Silkscreen Top")
		(7 "B.SilkS" user "Ref Des/Silkscreen Bottom")
		(1 "F.Mask" user "Board Geometry/Soldermask Top")
		(3 "B.Mask" user "Board Geometry/Soldermask Bottom")
		(17 "Dwgs.User" user "User.Drawings")
		(19 "Cmts.User" user "User.Comments")
		(21 "Eco1.User" user "User.Eco1")
		(23 "Eco2.User" user "User.Eco2")
		(25 "Edge.Cuts" user "Board Geometry/Outline")
		(27 "Margin" user)
		(31 "F.CrtYd" user "Package Geometry/Place Bound Top")
		(29 "B.CrtYd" user "Package Geometry/Place Bound Bottom")
		(35 "F.Fab" user "Ref Des/Assembly Top")
		(33 "B.Fab" user "Ref Des/Assembly Bottom")
	)
	(footprint ""
		(layer "B.Cu")
		(at 354.425758 -250.89231 180)
		(property "Reference" "C2170"
			(at 0 0 0)
			(layer "B.SilkS")
			(hide yes)
			(effects
				(font
					(size 1.27 1.27)
				)
				(justify mirror)
			)
		)
		(property "Value" ""
			(at 0 0 0)
			(layer "B.Fab")
			(effects
				(font
					(size 1.27 1.27)
				)
				(justify mirror)
			)
		)
		(duplicate_pad_numbers_are_jumpers no)
		(fp_line
			(start 0.7874 0.4064)
			(end 0.7874 -0.4064)
			(stroke
				(width 0.1524)
				(type default)
			)
			(layer "B.SilkS")
		)
		(fp_line
			(start 0.7874 -0.4064)
			(end -0.7874 -0.4064)
			(stroke
				(width 0.1524)
				(type default)
			)
			(layer "B.SilkS")
		)
		(fp_line
			(start -0.7874 0.4064)
			(end 0.7874 0.4064)
			(stroke
				(width 0.1524)
				(type default)
			)
			(layer "B.SilkS")
		)
		(fp_line
			(start -0.7874 -0.4064)
			(end -0.7874 0.4064)
			(stroke
				(width 0.1524)
				(type default)
			)
			(layer "B.SilkS")
		)
		(fp_line
			(start 0.67945 0.3048)
			(end 0.67945 -0.305054)
			(stroke
				(width 0.1)
				(type default)
			)
			(layer "B.Fab")
		)
		(fp_line
			(start 0.67945 -0.305054)
			(end 0.12065 -0.305054)
			(stroke
				(width 0.1)
				(type default)
			)
			(layer "B.Fab")
		)
		(fp_line
			(start 0.12065 0.3048)
			(end 0.67945 0.3048)
			(stroke
				(width 0.1)
				(type default)
			)
			(layer "B.Fab")
		)
		(fp_line
			(start 0.12065 0.2794)
			(end 0.12065 0.3048)
			(stroke
				(width 0.1)
				(type default)
			)
			(layer "B.Fab")
		)
		(fp_line
			(start 0.12065 -0.2794)
			(end -0.12065 -0.2794)
			(stroke
				(width 0.1)
				(type default)
			)
			(layer "B.Fab")
		)
		(fp_line
			(start 0.12065 -0.305054)
			(end 0.12065 -0.2794)
			(stroke
				(width 0.1)
				(type default)
			)
			(layer "B.Fab")
		)
		(fp_line
			(start -0.120396 0.3048)
			(end -0.120396 0.2794)
			(stroke
				(width 0.1)
				(type default)
			)
			(layer "B.Fab")
		)
		(fp_line
			(start -0.120396 0.2794)
			(end 0.12065 0.2794)
			(stroke
				(width 0.1)
				(type default)
			)
			(layer "B.Fab")
		)
		(fp_line
			(start -0.12065 -0.2794)
			(end -0.12065 -0.3048)
			(stroke
				(width 0.1)
				(type default)
			)
			(layer "B.Fab")
		)
		(fp_line
			(start -0.12065 -0.3048)
			(end -0.67945 -0.3048)
			(stroke
				(width 0.1)
				(type default)
			)
			(layer "B.Fab")
		)
		(fp_line
			(start -0.67945 0.3048)
			(end -0.120396 0.3048)
			(stroke
				(width 0.1)
				(type default)
			)
			(layer "B.Fab")
		)
		(fp_line
			(start -0.67945 -0.3048)
			(end -0.67945 0.3048)
			(stroke
				(width 0.1)
				(type default)
			)
			(layer "B.Fab")
		)
		(pad "1" smd circle
			(at 0.40005 0)
			(size 0 0)
			(layers "B.Cu" "B.Mask" "B.Paste")
			(net "PVDDCR_CPU0_P0")
		)
		(pad "2" smd circle
			(at -0.40005 0)
			(size 0 0)
			(layers "B.Cu" "B.Mask" "B.Paste")
			(net "GND")
		)
	)
	(footprint ""
		(layer "B.Cu")
		(at 208.461356 -383.612136)
		(property "Reference" "PR2518"
			(at 0 0 0)
			(layer "B.SilkS")
			(hide yes)
			(effects
				(font
					(size 1.27 1.27)
				)
				(justify mirror)
			)
		)
		(property "Value" ""
			(at 0 0 0)
			(layer "B.Fab")
			(effects
				(font
					(size 1.27 1.27)
				)
				(justify mirror)
			)
		)
		(duplicate_pad_numbers_are_jumpers no)
		(fp_line
			(start -0.7874 -0.4064)
			(end -0.7874 0.4064)
			(stroke
				(width 0.1524)
				(type default)
			)
			(layer "B.SilkS")
		)
		(fp_line
			(start -0.7874 0.4064)
			(end 0.7874 0.4064)
			(stroke
				(width 0.1524)
				(type default)
			)
			(layer "B.SilkS")
		)
		(fp_line
			(start 0.7874 -0.4064)
			(end -0.7874 -0.4064)
			(stroke
				(width 0.1524)
				(type default)
			)
			(layer "B.SilkS")
		)
		(fp_line
			(start 0.7874 0.4064)
			(end 0.7874 -0.4064)
			(stroke
				(width 0.1524)
				(type default)
			)
			(layer "B.SilkS")
		)
		(fp_line
			(start -0.67945 -0.3048)
			(end -0.67945 0.3048)
			(stroke
				(width 0.1)
				(type default)
			)
			(layer "B.Fab")
		)
		(fp_line
			(start -0.67945 0.3048)
			(end -0.120396 0.3048)
			(stroke
				(width 0.1)
				(type default)
			)
			(layer "B.Fab")
		)
		(fp_line
			(start -0.12065 -0.3048)
			(end -0.67945 -0.3048)
			(stroke
				(width 0.1)
				(type default)
			)
			(layer "B.Fab")
		)
		(fp_line
			(start -0.12065 -0.2794)
			(end -0.12065 -0.3048)
			(stroke
				(width 0.1)
				(type default)
			)
			(layer "B.Fab")
		)
		(fp_line
			(start -0.120396 0.2794)
			(end 0.12065 0.2794)
			(stroke
				(width 0.1)
				(type default)
			)
			(layer "B.Fab")
		)
		(fp_line
			(start -0.120396 0.3048)
			(end -0.120396 0.2794)
			(stroke
				(width 0.1)
				(type default)
			)
			(layer "B.Fab")
		)
		(fp_line
			(start 0.12065 -0.305054)
			(end 0.12065 -0.2794)
			(stroke
				(width 0.1)
				(type default)
			)
			(layer "B.Fab")
		)
		(fp_line
			(start 0.12065 -0.2794)
			(end -0.12065 -0.2794)
			(stroke
				(width 0.1)
				(type default)
			)
			(layer "B.Fab")
		)
		(fp_line
			(start 0.12065 0.2794)
			(end 0.12065 0.3048)
			(stroke
				(width 0.1)
				(type default)
			)
			(layer "B.Fab")
		)
		(fp_line
			(start 0.12065 0.3048)
			(end 0.67945 0.3048)
			(stroke
				(width 0.1)
				(type default)
			)
			(layer "B.Fab")
		)
		(fp_line
			(start 0.67945 -0.305054)
			(end 0.12065 -0.305054)
			(stroke
				(width 0.1)
				(type default)
			)
			(layer "B.Fab")
		)
		(fp_line
			(start 0.67945 0.3048)
			(end 0.67945 -0.305054)
			(stroke
				(width 0.1)
				(type default)
			)
			(layer "B.Fab")
		)
		(pad "1" smd circle
			(at 0.40005 0 180)
			(size 0 0)
			(layers "B.Cu" "B.Mask" "B.Paste")
			(net "P12V_HSC_ADC_N")
		)
		(pad "2" smd circle
			(at -0.40005 0 180)
			(size 0 0)
			(layers "B.Cu" "B.Mask" "B.Paste")
			(net "P12V_HSC_SENSE2_R4_N")
		)
	)
	(footprint ""
		(layer "B.Cu")
		(at 400.883882 -416.899344 90)
		(property "Reference" "C6615"
			(at 0 0 90)
			(layer "B.SilkS")
			(hide yes)
			(effects
				(font
					(size 1.27 1.27)
				)
				(justify mirror)
			)
		)
		(property "Value" ""
			(at 0 0 90)
			(layer "B.Fab")
			(effects
				(font
					(size 1.27 1.27)
				)
				(justify mirror)
			)
		)
		(duplicate_pad_numbers_are_jumpers no)
		(fp_line
			(start 0.299974 -0.150114)
			(end -0.299974 -0.150114)
			(stroke
				(width 0.1)
				(type default)
			)
			(layer "B.Fab")
		)
		(fp_line
			(start -0.299974 -0.150114)
			(end -0.299974 0.150114)
			(stroke
				(width 0.1)
				(type default)
			)
			(layer "B.Fab")
		)
		(fp_line
			(start 0.299974 0.150114)
			(end 0.299974 -0.150114)
			(stroke
				(width 0.1)
				(type default)
			)
			(layer "B.Fab")
		)
		(fp_line
			(start -0.299974 0.150114)
			(end 0.299974 0.150114)
			(stroke
				(width 0.1)
				(type default)
			)
			(layer "B.Fab")
		)
		(pad "1" smd rect
			(at 0.2667 0 270)
			(size 0.3048 0.381)
			(layers "B.Cu" "B.Mask" "B.Paste")
			(net "P5E_CPU0_P3_TX_BUF_C_DP<9>")
		)
		(pad "2" smd rect
			(at -0.2667 0 270)
			(size 0.3048 0.381)
			(layers "B.Cu" "B.Mask" "B.Paste")
			(net "P5E_CPU0_P3_TX_BUF_DP<9>")
		)
	)
	(footprint ""
		(layer "B.Cu")
		(at 312.674 -358.14 -90)
		(property "Reference" "PR532"
			(at 0 0 90)
			(layer "B.SilkS")
			(hide yes)
			(effects
				(font
					(size 1.27 1.27)
				)
				(justify mirror)
			)
		)
		(property "Value" ""
			(at 0 0 90)
			(layer "B.Fab")
			(effects
				(font
					(size 1.27 1.27)
				)
				(justify mirror)
			)
		)
		(duplicate_pad_numbers_are_jumpers no)
		(fp_line
			(start -0.7874 0.4064)
			(end 0.7874 0.4064)
			(stroke
				(width 0.1524)
				(type default)
			)
			(layer "B.SilkS")
		)
		(fp_line
			(start 0.7874 0.4064)
			(end 0.7874 -0.4064)
			(stroke
				(width 0.1524)
				(type default)
			)
			(layer "B.SilkS")
		)
		(fp_line
			(start -0.7874 -0.4064)
			(end -0.7874 0.4064)
			(stroke
				(width 0.1524)
				(type default)
			)
			(layer "B.SilkS")
		)
		(fp_line
			(start 0.7874 -0.4064)
			(end -0.7874 -0.4064)
			(stroke
				(width 0.1524)
				(type default)
			)
			(layer "B.SilkS")
		)
		(fp_line
			(start -0.67945 0.3048)
			(end -0.120396 0.3048)
			(stroke
				(width 0.1)
				(type default)
			)
			(layer "B.Fab")
		)
		(fp_line
			(start -0.120396 0.3048)
			(end -0.120396 0.2794)
			(stroke
				(width 0.1)
				(type default)
			)
			(layer "B.Fab")
		)
		(fp_line
			(start 0.12065 0.3048)
			(end 0.67945 0.3048)
			(stroke
				(width 0.1)
				(type default)
			)
			(layer "B.Fab")
		)
		(fp_line
			(start 0.67945 0.3048)
			(end 0.67945 -0.305054)
			(stroke
				(width 0.1)
				(type default)
			)
			(layer "B.Fab")
		)
		(fp_line
			(start -0.120396 0.2794)
			(end 0.12065 0.2794)
			(stroke
				(width 0.1)
				(type default)
			)
			(layer "B.Fab")
		)
		(fp_line
			(start 0.12065 0.2794)
			(end 0.12065 0.3048)
			(stroke
				(width 0.1)
				(type default)
			)
			(layer "B.Fab")
		)
		(fp_line
			(start -0.12065 -0.2794)
			(end -0.12065 -0.3048)
			(stroke
				(width 0.1)
				(type default)
			)
			(layer "B.Fab")
		)
		(fp_line
			(start 0.12065 -0.2794)
			(end -0.12065 -0.2794)
			(stroke
				(width 0.1)
				(type default)
			)
			(layer "B.Fab")
		)
		(fp_line
			(start -0.67945 -0.3048)
			(end -0.67945 0.3048)
			(stroke
				(width 0.1)
				(type default)
			)
			(layer "B.Fab")
		)
		(fp_line
			(start -0.12065 -0.3048)
			(end -0.67945 -0.3048)
			(stroke
				(width 0.1)
				(type default)
			)
			(layer "B.Fab")
		)
		(fp_line
			(start 0.12065 -0.305054)
			(end 0.12065 -0.2794)
			(stroke
				(width 0.1)
				(type default)
			)
			(layer "B.Fab")
		)
		(fp_line
			(start 0.67945 -0.305054)
			(end 0.12065 -0.305054)
			(stroke
				(width 0.1)
				(type default)
			)
			(layer "B.Fab")
		)
		(pad "1" smd circle
			(at 0.40005 0 90)
			(size 0 0)
			(layers "B.Cu" "B.Mask" "B.Paste")
			(net "NC_PVDDCR_CPU1_P0_IMON7")
		)
		(pad "2" smd circle
			(at -0.40005 0 90)
			(size 0 0)
			(layers "B.Cu" "B.Mask" "B.Paste")
			(net "GND")
		)
	)
	(footprint ""
		(layer "B.Cu")
		(at 10.91057 -383.051558 -90)
		(property "Reference" "PC6625_1"
			(at 0 0 90)
			(layer "B.SilkS")
			(hide yes)
			(effects
				(font
					(size 1.27 1.27)
				)
				(justify mirror)
			)
		)
		(property "Value" ""
			(at 0 0 90)
			(layer "B.Fab")
			(effects
				(font
					(size 1.27 1.27)
				)
				(justify mirror)
			)
		)
		(duplicate_pad_numbers_are_jumpers no)
		(fp_line
			(start -1.524 0.762)
			(end 1.524 0.762)
			(stroke
				(width 0.1524)
				(type default)
			)
			(layer "B.SilkS")
		)
		(fp_line
			(start 1.524 0.762)
			(end 1.524 -0.762)
			(stroke
				(width 0.1524)
				(type default)
			)
			(layer "B.SilkS")
		)
		(fp_line
			(start -1.524 -0.762)
			(end -1.524 0.762)
			(stroke
				(width 0.1524)
				(type default)
			)
			(layer "B.SilkS")
		)
		(fp_line
			(start 1.524 -0.762)
			(end -1.524 -0.762)
			(stroke
				(width 0.1524)
				(type default)
			)
			(layer "B.SilkS")
		)
		(fp_line
			(start -1.1049 0.724916)
			(end -1.1049 -0.724916)
			(stroke
				(width 0.1)
				(type default)
			)
			(layer "B.Fab")
		)
		(fp_line
			(start 1.1049 0.724916)
			(end -1.1049 0.724916)
			(stroke
				(width 0.1)
				(type default)
			)
			(layer "B.Fab")
		)
		(fp_line
			(start -1.1049 -0.724916)
			(end 1.1049 -0.724916)
			(stroke
				(width 0.1)
				(type default)
			)
			(layer "B.Fab")
		)
		(fp_line
			(start 1.1049 -0.724916)
			(end 1.1049 0.724916)
			(stroke
				(width 0.1)
				(type default)
			)
			(layer "B.Fab")
		)
		(pad "1" smd rect
			(at 0.889 0 270)
			(size 1.016 1.27)
			(layers "B.Cu" "B.Mask" "B.Paste")
			(net "P0V9_CPU1_RT_2D")
		)
		(pad "2" smd rect
			(at -0.889 0 270)
			(size 1.016 1.27)
			(layers "B.Cu" "B.Mask" "B.Paste")
			(net "GND")
		)
	)
	(footprint ""
		(layer "B.Cu")
		(at 162.7124 -424.60037 -90)
		(property "Reference" "R1512"
			(at 0 0 90)
			(layer "B.SilkS")
			(hide yes)
			(effects
				(font
					(size 1.27 1.27)
				)
				(justify mirror)
			)
		)
		(property "Value" ""
			(at 0 0 90)
			(layer "B.Fab")
			(effects
				(font
					(size 1.27 1.27)
				)
				(justify mirror)
			)
		)
		(duplicate_pad_numbers_are_jumpers no)
		(fp_line
			(start -0.32512 0.175006)
			(end 0.32512 0.175006)
			(stroke
				(width 0.1)
				(type default)
			)
			(layer "B.Fab")
		)
		(fp_line
			(start 0.32512 0.175006)
			(end 0.32512 -0.175006)
			(stroke
				(width 0.1)
				(type default)
			)
			(layer "B.Fab")
		)
		(fp_line
			(start -0.32512 -0.175006)
			(end -0.32512 0.175006)
			(stroke
				(width 0.1)
				(type default)
			)
			(layer "B.Fab")
		)
		(fp_line
			(start 0.32512 -0.175006)
			(end -0.32512 -0.175006)
			(stroke
				(width 0.1)
				(type default)
			)
			(layer "B.Fab")
		)
		(pad "1" smd rect
			(at 0.2667 0 90)
			(size 0.3048 0.381)
			(layers "B.Cu" "B.Mask" "B.Paste")
			(net "P1V8_CPU1_RT_1D")
		)
		(pad "2" smd rect
			(at -0.2667 0 270)
			(size 0.3048 0.381)
			(layers "B.Cu" "B.Mask" "B.Paste")
			(net "JTAG_TDO_RT_CPU1_P3")
		)
	)
	(footprint ""
		(layer "B.Cu")
		(at 403.018752 -398.942052 90)
		(property "Reference" "C803"
			(at 0 0 90)
			(layer "B.SilkS")
			(hide yes)
			(effects
				(font
					(size 1.27 1.27)
				)
				(justify mirror)
			)
		)
		(property "Value" ""
			(at 0 0 90)
			(layer "B.Fab")
			(effects
				(font
					(size 1.27 1.27)
				)
				(justify mirror)
			)
		)
		(duplicate_pad_numbers_are_jumpers no)
		(fp_line
			(start 0.7874 -0.4064)
			(end -0.7874 -0.4064)
			(stroke
				(width 0.1524)
				(type default)
			)
			(layer "B.SilkS")
		)
		(fp_line
			(start -0.7874 -0.4064)
			(end -0.7874 0.4064)
			(stroke
				(width 0.1524)
				(type default)
			)
			(layer "B.SilkS")
		)
		(fp_line
			(start 0.7874 0.4064)
			(end 0.7874 -0.4064)
			(stroke
				(width 0.1524)
				(type default)
			)
			(layer "B.SilkS")
		)
		(fp_line
			(start -0.7874 0.4064)
			(end 0.7874 0.4064)
			(stroke
				(width 0.1524)
				(type default)
			)
			(layer "B.SilkS")
		)
		(fp_line
			(start 0.67945 -0.305054)
			(end 0.12065 -0.305054)
			(stroke
				(width 0.1)
				(type default)
			)
			(layer "B.Fab")
		)
		(fp_line
			(start 0.12065 -0.305054)
			(end 0.12065 -0.2794)
			(stroke
				(width 0.1)
				(type default)
			)
			(layer "B.Fab")
		)
		(fp_line
			(start -0.12065 -0.3048)
			(end -0.67945 -0.3048)
			(stroke
				(width 0.1)
				(type default)
			)
			(layer "B.Fab")
		)
		(fp_line
			(start -0.67945 -0.3048)
			(end -0.67945 0.3048)
			(stroke
				(width 0.1)
				(type default)
			)
			(layer "B.Fab")
		)
		(fp_line
			(start 0.12065 -0.2794)
			(end -0.12065 -0.2794)
			(stroke
				(width 0.1)
				(type default)
			)
			(layer "B.Fab")
		)
		(fp_line
			(start -0.12065 -0.2794)
			(end -0.12065 -0.3048)
			(stroke
				(width 0.1)
				(type default)
			)
			(layer "B.Fab")
		)
		(fp_line
			(start 0.12065 0.2794)
			(end 0.12065 0.3048)
			(stroke
				(width 0.1)
				(type default)
			)
			(layer "B.Fab")
		)
		(fp_line
			(start -0.120396 0.2794)
			(end 0.12065 0.2794)
			(stroke
				(width 0.1)
				(type default)
			)
			(layer "B.Fab")
		)
		(fp_line
			(start 0.67945 0.3048)
			(end 0.67945 -0.305054)
			(stroke
				(width 0.1)
				(type default)
			)
			(layer "B.Fab")
		)
		(fp_line
			(start 0.12065 0.3048)
			(end 0.67945 0.3048)
			(stroke
				(width 0.1)
				(type default)
			)
			(layer "B.Fab")
		)
		(fp_line
			(start -0.120396 0.3048)
			(end -0.120396 0.2794)
			(stroke
				(width 0.1)
				(type default)
			)
			(layer "B.Fab")
		)
		(fp_line
			(start -0.67945 0.3048)
			(end -0.120396 0.3048)
			(stroke
				(width 0.1)
				(type default)
			)
			(layer "B.Fab")
		)
		(pad "1" smd circle
			(at 0.40005 0 270)
			(size 0 0)
			(layers "B.Cu" "B.Mask" "B.Paste")
			(net "P0V9_CPU0_RT2_2A")
		)
		(pad "2" smd circle
			(at -0.40005 0 270)
			(size 0 0)
			(layers "B.Cu" "B.Mask" "B.Paste")
			(net "GND")
		)
	)
)
